FILE_TYPE = CONNECTIVITY;
{Allegro Design Entry HDL 17.4-2019 S026 (4007227) 1/17/2022}
"PAGE_NUMBER" = 202;
0"NC";
END.
